FILE_TYPE = CONNECTIVITY;
{Allegro Design Entry HDL 16.6-p007 (v16-6-112F) 10/10/2012}
"PAGE_NUMBER" = 241;
0"NC";
1"GND\g";
2"GND\g";
3"GND\g";
4"AGND_P5V_STBY\g";
5"GND\g";
6"GND\g";
7"GND\g";
8"GND\g";
9"AGND_P5V_STBY\g";
10"AGND_P5V_STBY\g";
11"GND\g";
12"AGND_P5V_STBY\g";
13"P5V_STBY\g";
14"P12V_STBY\g";
15"P5V_STBY\g";
16"AGND_P5V_STBY\g";
17"VR_FET_SW_P5V_STBY_PVIN";
18"PWRGD_P5V_STBY";
19"PWRGD_P5V_STBY_R";
20"VR_P5V_STBY_PHASE";
21"VR_P5V_STBY_VSENSE_R";
22"VR_P5V_STBY_VSENSE";
23"VR_P5V_STBY_BOOT";
24"VR_P5V_STBY_COMP";
25"VR_P5V_STBY_RC_COMP";
26"VR_P5V_STBY_VIN";
27"VR_P5V_STBY_RT";
28"VR_P5V_STBY_EN";
29"VR_P5V_STBY_SS";
30"PWRGD_P12V_HSC_DLY";
%"RES"
"2","(1225,4850)","0","mstr_discrete","I11";
;
CDS_SEC"1"
SEC_TYPE"0402"
REUSE_ID"21"
BOM_COST"P5V_STBY_VR"
SEC"1"
ROOM"P5V_STBY_VR"
CDS_LOCATION"R7E12"
CDS_LIB"mstr_discrete"
LOCATION"R7E12"
VALUE"1.00K"
TOLERANCE"1%"
PACK_TYPE"0402"
MATERIAL"CHIP"
WATTAGE"1/16W"
PART_NUMBER"G21796-026";
"A"
$PN"1"15;
"B"
$PN"2"19;
%"CAP"
"2","(1025,3675)","0","mstr_discrete","I12";
;
CDS_SEC"1"
SEC_TYPE"0603LF"
SEC"1"
SPOF"TRUE"
REUSE_ID"27"
BOM_COST"P5V_STBY_VR"
CDS_LIB"mstr_discrete"
CDS_LOCATION"C8E6"
ROOM"P5V_STBY_VR"
PACK_TYPE"0603LF"
VOLTAGE"25V"
MATERIAL"X7R"
LOCATION"C8E6"
PART_NUMBER"602433-020"
TOLERANCE"10%"
VALUE"0.1UF";
"A"
$PN"1"23;
"B"
$PN"2"20;
%"CAP"
"1","(1500,4400)","0","mstr_discrete","I14";
;
CDS_SEC"1"
SEC"1"
REUSE_ID"17"
SEC_TYPE"0402LF"
ROOM"P5V_STBY_VR"
CDS_LOCATION"C7E10"
BOM_COST"P5V_STBY_VR"
CDS_LIB"mstr_discrete"
MATERIAL"X7R"
VOLTAGE"50V"
PACK_TYPE"0402LF"
TOLERANCE"10%"
VALUE"1000PF"
LOCATION"C7E10"
PART_NUMBER"A36096-046";
"A"
$PN"1"19;
"B"
$PN"2"1;
%"GND"
"1","(1500,4150)","0","mstr_symbols","I16";
;
SIZE"1B"
VOLTAGE"0"
CDS_LIB"mstr_symbols"
BODY_TYPE"PLUMBING"
HDL_POWER"GND";
"A\NAC"1;
%"RES"
"2","(-825,2600)","0","mstr_discrete","I18";
;
CDS_SEC"1"
SEC_TYPE"0402"
SEC"1"
BOM_COST"P5V_STBY_VR"
ROOM"P5V_STBY_VR"
REUSE_ID"8"
CDS_LOCATION"R7E14"
CDS_LIB"mstr_discrete"
PART_NUMBER"G21796-224"
LOCATION"R7E14"
VALUE"75K"
TOLERANCE"1%"
WATTAGE"1/16W"
PACK_TYPE"0402"
MATERIAL"CHIP";
"A"
$PN"1"27;
"B"
$PN"2"12;
%"GND"
"1","(675,3125)","0","mstr_symbols","I19";
;
HDL_POWER"GND"
SIZE"1B"
CDS_LIB"mstr_symbols"
VOLTAGE"0"
BODY_TYPE"PLUMBING";
"A\NAC"2;
%"CAP"
"1","(3700,3875)","0","mstr_discrete","I2";
;
CDS_SEC"1"
SEC_TYPE"0805"
BOM_COST"P5V_STBY_VR"
$REUSE_ID"33"
SEC"1"
CDS_LIB"mstr_discrete"
CDS_LOCATION"C8E9"
ROOM"P5V_STBY_VR"
VOLTAGE"6.3V"
PACK_TYPE"0805"
LOCATION"C8E9"
VALUE"22UF"
PART_NUMBER"C95333-008"
TOLERANCE"20%"
MATERIAL"X6S";
"A"
$PN"1"13;
"B"
$PN"2"5;
%"CAP"
"1","(3325,3900)","0","mstr_discrete","I3";
;
CDS_SEC"1"
REUSE_ID"33"
SEC_TYPE"0805"
SEC"1"
BOM_COST"P5V_STBY_VR"
CDS_LOCATION"C8E7"
ROOM"P5V_STBY_VR"
CDS_LIB"mstr_discrete"
PACK_TYPE"0805"
MATERIAL"X6S"
LOCATION"C8E7"
VALUE"22UF"
TOLERANCE"20%"
VOLTAGE"6.3V"
PART_NUMBER"C95333-008";
"A"
$PN"1"13;
"B"
$PN"2"5;
%"CAP"
"1","(-2150,3850)","0","mstr_discrete","I30";
;
CDS_SEC"1"
FIN"VR_1P2"
REUSE_ID"1"
SEC_TYPE"0402"
ROOM"P5V_STBY_VR"
SEC"1"
BOM_COST"P5V_STBY_VR"
CDS_LIB"mstr_discrete"
CDS_LOCATION"C7E14"
LOCATION"C7E14"
VALUE"1.0UF"
TOLERANCE"10%"
PACK_TYPE"0402"
VOLTAGE"16V"
MATERIAL"X6S"
PART_NUMBER"D97712-011";
"A"
$PN"1"26;
"B"
$PN"2"3;
%"GND"
"1","(-2150,3550)","0","mstr_symbols","I31";
;
HDL_POWER"GND"
VOLTAGE"0"
CDS_LIB"mstr_symbols"
SIZE"1B"
BODY_TYPE"PLUMBING";
"A\NAC"3;
%"GND"
"1","(-2000,2700)","0","mstr_symbols","I32";
;
VOLTAGE"0"
SIZE"1B"
CDS_LIB"mstr_symbols"
BODY_TYPE"PLUMBING"
HDL_POWER"AGND_P5V_STBY";
"A\NAC"4;
%"RES"
"2","(-2150,4200)","0","mstr_discrete","I37";
;
CDS_SEC"1"
NO_XNET_CONNECTION"1"
$REUSE_ID"13"
SEC_TYPE"0402"
ROOM"P5V_STBY_VR"
BOM_COST"P5V_STBY_VR"
SEC"1"
CDS_LOCATION"R7E17"
CDS_LIB"mstr_discrete"
LOCATION"R7E17"
VALUE"0.0"
TOLERANCE"5%"
MATERIAL"CHIP"
WATTAGE"1/16W"
PART_NUMBER"G21497-005"
PACK_TYPE"0402";
"A"
$PN"1"17;
"B"
$PN"2"26;
%"CAP"
"1","(-2550,4250)","0","mstr_discrete","I39";
;
CDS_SEC"1"
BOM_COST"P5V_STBY_VR"
SEC_TYPE"1206LF"
SEC"1"
ROOM"P5V_STBY_VR"
CDS_LIB"mstr_discrete"
CDS_LOCATION"C7E11"
TOLERANCE"10%"
LOCATION"C7E11"
VALUE"22UF"
MATERIAL"X6S"
VOLTAGE"16V"
PART_NUMBER"D38464-005"
PACK_TYPE"1206LF";
"A"
$PN"1"17;
"B"
$PN"2"6;
%"GND"
"1","(3600,3475)","0","mstr_symbols","I4";
;
HDL_POWER"GND"
VOLTAGE"0"
SIZE"1B"
CDS_LIB"mstr_symbols"
BODY_TYPE"PLUMBING";
"A\NAC"5;
%"GND"
"1","(-2550,4025)","0","mstr_symbols","I40";
;
HDL_POWER"GND"
CDS_LIB"mstr_symbols"
VOLTAGE"0"
SIZE"1B"
BODY_TYPE"PLUMBING";
"A\NAC"6;
%"CAP"
"1","(-2000,3075)","2","mstr_discrete","I41";
;
CDS_SEC"1"
CDS_LIB"mstr_discrete"
FIN"VR_1P2"
SEC_TYPE"0402LF"
REUSE_ID"1"
BOM_COST"P5V_STBY_VR"
SEC"1"
CDS_LOCATION"C8E13"
ROOM"P5V_STBY_VR"
PART_NUMBER"A36096-046"
LOCATION"C8E13"
VALUE"1000PF"
MATERIAL"EMPTY"
TOLERANCE"10%"
PACK_TYPE"0402LF"
VOLTAGE"50V";
"A"
$PN"1"30;
"B"
$PN"2"4;
%"GND"
"1","(-2875,4025)","0","mstr_symbols","I44";
;
HDL_POWER"GND"
VOLTAGE"0"
CDS_LIB"mstr_symbols"
SIZE"1B"
BODY_TYPE"PLUMBING";
"A\NAC"7;
%"CAP"
"1","(-2875,4275)","0","mstr_discrete","I45";
;
CDS_SEC"1"
ROOM"P5V_STBY_VR"
SEC"1"
BOM_COST"P5V_STBY_VR"
SEC_TYPE"1210"
CDS_LOCATION"C7E13"
CDS_LIB"mstr_discrete"
PART_NUMBER"D38464-007"
LOCATION"C7E13"
VALUE"47UF"
TOLERANCE"20%"
VOLTAGE"16V"
MATERIAL"X6S"
PACK_TYPE"1210";
"A"
$PN"1"17;
"B"
$PN"2"7;
%"GND"
"1","(-3225,4025)","0","mstr_symbols","I46";
;
HDL_POWER"GND"
VOLTAGE"0"
SIZE"1B"
CDS_LIB"mstr_symbols"
BODY_TYPE"PLUMBING";
"A\NAC"8;
%"CAP"
"1","(-3225,4275)","0","mstr_discrete","I47";
;
CDS_SEC"1"
SEC"1"
BOM_COST"P5V_STBY_VR"
SEC_TYPE"1210"
ROOM"P5V_STBY_VR"
CDS_LOCATION"C7E12"
CDS_LIB"mstr_discrete"
MATERIAL"X6S"
PACK_TYPE"1210"
LOCATION"C7E12"
VALUE"47UF"
TOLERANCE"20%"
VOLTAGE"16V"
PART_NUMBER"D38464-007";
"A"
$PN"1"17;
"B"
$PN"2"8;
%"RES"
"2","(1750,3425)","0","mstr_discrete","I50";
;
CDS_SEC"1"
BOM_COST"P5V_STBY_VR"
SPOF"TRUE"
SEC"1"
ROOM"P5V_STBY_VR"
REUSE_ID"9"
SEC_TYPE"0402"
CDS_LOCATION"R7F1"
CDS_LIB"mstr_discrete"
LOCATION"R7F1"
VALUE"10.0K"
TOLERANCE"1%"
PACK_TYPE"0402"
MATERIAL"CHIP"
WATTAGE"1/16W"
PART_NUMBER"G21796-016";
"A"
$PN"1"21;
"B"
$PN"2"22;
%"RES"
"2","(1750,2900)","0","mstr_discrete","I51";
;
CDS_SEC"1"
SEC_TYPE"0402"
BOM_COST"P5V_STBY_VR"
SPOF"TRUE"
REUSE_ID"7"
SEC"1"
ROOM"P5V_STBY_VR"
CDS_LOCATION"R7E16"
CDS_LIB"mstr_discrete"
LOCATION"R7E16"
VALUE"1.37K"
TOLERANCE"1%"
PACK_TYPE"0402"
MATERIAL"CHIP"
WATTAGE"1/16W"
PART_NUMBER"G21796-095";
"A"
$PN"1"22;
"B"
$PN"2"9;
%"GND"
"1","(1750,2625)","0","mstr_symbols","I52";
;
SIZE"1B"
VOLTAGE"0"
CDS_LIB"mstr_symbols"
BODY_TYPE"PLUMBING"
HDL_POWER"AGND_P5V_STBY";
"A\NAC"9;
%"CAP"
"2","(200,2575)","0","mstr_discrete","I53";
;
CDS_SEC"1"
SEC_TYPE"0402LF"
CDS_LIB"mstr_discrete"
REUSE_ID"4"
BOM_COST"P5V_STBY_VR"
SEC"1"
CDS_LOCATION"C8E16"
ROOM"P5V_STBY_VR"
LOCATION"C8E16"
PART_NUMBER"A36096-065"
VALUE"270PF"
PACK_TYPE"0402LF"
VOLTAGE"50V"
MATERIAL"X7R"
TOLERANCE"10%";
"A"
$PN"1"24;
"B"
$PN"2"16;
%"RES"
"1","(-200,2200)","0","mstr_discrete","I54";
;
CDS_SEC"1"
BOM_COST"P5V_STBY_VR"
SEC"1"
SEC_TYPE"0402"
REUSE_ID"10"
ROOM"P5V_STBY_VR"
CDS_LIB"mstr_discrete"
CDS_LOCATION"R8E39"
TOLERANCE"1%"
PACK_TYPE"0402"
LOCATION"R8E39"
PART_NUMBER"G21796-254"
VALUE"24.9K"
MATERIAL"CHIP"
WATTAGE"1/16W";
"B"
$PN"2"25;
"A"
$PN"1"24;
%"GND"
"1","(1925,1325)","0","mstr_symbols","I55";
;
VOLTAGE"0"
SIZE"1B"
CDS_LIB"mstr_symbols"
BODY_TYPE"PLUMBING"
HDL_POWER"AGND_P5V_STBY";
"A\NAC"10;
%"CAP"
"2","(575,2200)","0","mstr_discrete","I57";
;
CDS_SEC"1"
ROOM"P5V_STBY_VR"
SEC"1"
BOM_COST"P5V_STBY_VR"
REUSE_ID"5"
SEC_TYPE"0402LF"
CDS_LOCATION"C8F1"
CDS_LIB"mstr_discrete"
LOCATION"C8F1"
VOLTAGE"50V"
PART_NUMBER"A36096-075"
VALUE"2200PF"
TOLERANCE"10%"
MATERIAL"X7R"
PACK_TYPE"0402LF";
"A"
$PN"1"25;
"B"
$PN"2"16;
%"RES"
"1","(1575,1550)","0","mstr_discrete","I58";
;
CDS_SEC"1"
CDS_LIB"mstr_discrete"
SPOF"TRUE"
$REUSE_ID"13"
SEC_TYPE"0402"
BOM_COST"P5V_STBY_VR"
SEC"1"
CDS_LOCATION"R7E13"
ROOM"P5V_STBY_VR"
TOLERANCE"5%"
PACK_TYPE"0402"
MATERIAL"CHIP"
LOCATION"R7E13"
PART_NUMBER"G21497-005"
VALUE"0.0"
WATTAGE"1/16W";
"B"
$PN"2"10;
"A"
$PN"1"11;
%"GND"
"1","(1350,1325)","0","mstr_symbols","I59";
;
HDL_POWER"GND"
BODY_TYPE"PLUMBING"
SIZE"1B"
CDS_LIB"mstr_symbols"
VOLTAGE"0";
"A\NAC"11;
%"CAP"
"1","(-1025,3000)","2","mstr_discrete","I63";
;
CDS_SEC"1"
ROOM"P5V_STBY_VR"
CDS_LOCATION"C8E15"
SEC"1"
BOM_COST"P5V_STBY_VR"
REUSE_ID"16"
SEC_TYPE"0402LF"
CDS_LIB"mstr_discrete"
PART_NUMBER"A36096-073"
LOCATION"C8E15"
VALUE"0.022UF"
TOLERANCE"10%"
PACK_TYPE"0402LF"
VOLTAGE"16V"
MATERIAL"X7R";
"A"
$PN"1"29;
"B"
$PN"2"12;
%"GND"
"1","(-925,2200)","0","mstr_symbols","I64";
;
VOLTAGE"0"
CDS_LIB"mstr_symbols"
SIZE"1B"
BODY_TYPE"PLUMBING"
HDL_POWER"AGND_P5V_STBY";
"A\NAC"12;
%"P5V_STBY"
"1","(3175,4325)","0","mstr_symbols","I69";
;
SIZE"1B"
CDS_LIB"mstr_symbols"
VOLTAGE"+5"
BODY_TYPE"PLUMBING"
HDL_POWER"P5V_STBY";
"G\NAC"13;
%"P12V_STBY"
"1","(-3525,4875)","0","mstr_symbols","I71";
;
CDS_LIB"mstr_symbols"
SIZE"1B"
BODY_TYPE"PLUMBING"
VOLTAGE"12.0V"
HDL_POWER"P12V_STBY";
"G\NAC"14;
%"RES"
"1","(2075,3650)","0","mstr_discrete","I78";
;
CDS_SEC"1"
CDS_LIB"mstr_discrete"
MATERIAL"CHIP"
SEC_TYPE"0402"
BOM_COST"P5V_STBY_VR"
SEC"1"
ROOM"P5V_STBY_VR"
CDS_LOCATION"R8E37"
PART_NUMBER"G21497-005"
TOLERANCE"5%"
PACK_TYPE"0402"
WATTAGE"1/16W"
SPOF"TRUE"
LOCATION"R8E37"
VALUE"0.0";
"B"
$PN"2"13;
"A"
$PN"1"21;
%"CAPP"
"3","(2950,3875)","6","mstr_discrete","I8";
;
CDS_SEC"1"
CDS_LIB"mstr_discrete"
SEC_TYPE"3018"
REUSE_ID"28"
SEC"1"
CDS_LOCATION"C8E4"
LOCATION"C8E4"
VALUE"470UF"
TOLERANCE"20%"
PACK_TYPE"3018"
VOLTAGE"6.3V"
MATERIAL"POSCAP"
PART_NUMBER"724613-091";
"A"
$PN"1"13;
"B"
$PN"2"5;
%"FERRITE"
"1","(-3300,4675)","0","mstr_discrete","I82";
;
CDS_LIB"mstr_discrete"
$SEC"1"
CDS_SEC"1"
BOM_COST"P5V_STBY_VR"
ROOM"P5V_STBY_VR"
CDS_LOCATION"FB7E1"
LOCATION"FB7E1"
PART_NUMBER"656554-051"
PACK_TYPE"SM"
MATERIAL"FB"
VALUE"22";
"A"
$PN"1"14;
"B"
$PN"2"17;
%"TPS54821"
"1","(125,3575)","0","mstr_vreg","I83";
;
CDS_SEC"1"
CDS_LIB"mstr_vreg"
BOM_COST"P5V_STBY_VR"
PACK_TYPE"LCC"
SEC_TYPE"LCC"
SEC"1"
ROOM"P5V_STBY_VR"
CDS_LOCATION"EU7E2"
PART_NUMBER"H63269-001"
MATERIAL"IC"
LOCATION"EU7E2";
"BOOT"
$PN"13"23;
"PWRGD"
$PN"14"19;
"VIN"
$PN"6"26;
"EN"
$PN"10"28;
"SS_TR"
$PN"9"29;
"RT_CLK"
$PN"1"27;
"COMP"
$PN"8"24;
"PVIN<1>"
$PN"5"17;
"PVIN<0>"
$PN"4"17;
"GND<1>"
$PN"3"2;
"GND<0>"
$PN"2"2;
"THPAD"
$PN"15"2;
"PH<1>"
$PN"12"20;
"PH<0>"
$PN"11"20;
"VSENSE"
$PN"7"22;
%"P5V_STBY"
"1","(1225,5050)","0","mstr_symbols","I85";
;
VOLTAGE"+5.0V"
CDS_LIB"mstr_symbols"
SIZE"1B"
BODY_TYPE"PLUMBING"
HDL_POWER"P5V_STBY";
"G\NAC"15;
%"GND"
"1","(975,2075)","0","mstr_symbols","I86";
;
CDS_LIB"mstr_symbols"
VOLTAGE"0"
SIZE"1B"
BODY_TYPE"PLUMBING"
HDL_POWER"AGND_P5V_STBY";
"A\NAC"16;
%"RES"
"1","(2250,4625)","0","mstr_discrete","I89";
;
CDS_SEC"1"
SEC_TYPE"0402"
ROOM"P5V_STBY_VR"
CDS_LIB"mstr_discrete"
SEC"1"
CDS_LOCATION"R7E15"
PACK_TYPE"0402"
LOCATION"R7E15"
PART_NUMBER"G21796-250"
VALUE"22.1"
TOLERANCE"1.0%"
MATERIAL"CHIP"
WATTAGE"1/16W";
"B"
$PN"2"18;
"A"
$PN"1"19;
%"RES"
"2","(2550,3875)","0","mstr_discrete","I9";
;
CDS_SEC"1"
SEC_TYPE"0402"
REUSE_ID"34"
SEC"1"
BOM_COST"P5V_STBY_VR"
CDS_LOCATION"R8E18"
ROOM"P5V_STBY_VR"
CDS_LIB"mstr_discrete"
LOCATION"R8E18"
VALUE"1.0K"
TOLERANCE"0.1%"
PACK_TYPE"0402"
MATERIAL"CHIP"
WATTAGE"1/16W"
PART_NUMBER"G85996-004";
"A"
$PN"1"13;
"B"
$PN"2"5;
%"INDUCTOR"
"1","(2150,4075)","0","mstr_discrete","I90";
;
$SEC"1"
CDS_SEC"1"
CDS_LOCATION"L8E1"
CDS_LIB"mstr_discrete"
LOCATION"L8E1"
PART_NUMBER"E98761-003"
PACK_TYPE"SM"
MATERIAL"IND"
VALUE"2.2UH";
"INA\NAC"
$PN"1"20;
"INB\NAC"
$PN"2"13;
%"RES"
"1","(-1625,3475)","0","mstr_discrete","I91";
;
CDS_SEC"1"
SEC_TYPE"0402"
SEC"1"
ROOM"PVCCIN_CPU0_VR"
CDS_LIB"mstr_discrete"
CDS_LOCATION"R8E33"
LOCATION"R8E33"
PART_NUMBER"G21497-005"
PACK_TYPE"0402"
MATERIAL"CHIP"
TOLERANCE"5%"
VALUE"0.0"
WATTAGE"1/16W";
"B"
$PN"2"28;
"A"
$PN"1"30;
END.
